(kicad_pcb
	(version 20260206)
	(generator "pcbnew")
	(generator_version "10.0")
	(general
		(thickness 1.6)
		(legacy_teardrops no)
	)
	(paper "A4")
	(title_block
		(title "03242023_DA0F0TMBIJ0_F0T_Motherboard_J_brd_V01_OCP.brd")
		(comment 1 "Grand Teton / footprints 3141-3146 of 6105")
	)
	(layers
		(0 "F.Cu" signal "TOP")
		(4 "In1.Cu" signal "GND")
		(6 "In2.Cu" signal "IN1")
		(8 "In3.Cu" signal "GND1")
		(10 "In4.Cu" signal "IN2")
		(12 "In5.Cu" signal "GND2")
		(14 "In6.Cu" signal "IN3")
		(16 "In7.Cu" signal "GND3")
		(18 "In8.Cu" signal "VCC")
		(20 "In9.Cu" signal "VCC1")
		(22 "In10.Cu" signal "GND4")
		(24 "In11.Cu" signal "IN4")
		(26 "In12.Cu" signal "GND5")
		(28 "In13.Cu" signal "IN5")
		(30 "In14.Cu" signal "GND6")
		(32 "In15.Cu" signal "IN6")
		(34 "In16.Cu" signal "GND7")
		(2 "B.Cu" signal "BOTTOM")
		(9 "F.Adhes" user "F.Adhesive")
		(11 "B.Adhes" user "B.Adhesive")
		(13 "F.Paste" user "Package Geometry/Pastemask Top")
		(15 "B.Paste" user "Package Geometry/Pastemask Bottom")
		(5 "F.SilkS" user "Ref Des/Silkscreen Top")
		(7 "B.SilkS" user "Ref Des/Silkscreen Bottom")
		(1 "F.Mask" user "Board Geometry/Soldermask Top")
		(3 "B.Mask" user "Board Geometry/Soldermask Bottom")
		(17 "Dwgs.User" user "User.Drawings")
		(19 "Cmts.User" user "User.Comments")
		(21 "Eco1.User" user "User.Eco1")
		(23 "Eco2.User" user "User.Eco2")
		(25 "Edge.Cuts" user "Board Geometry/Outline")
		(27 "Margin" user)
		(31 "F.CrtYd" user "Package Geometry/Place Bound Top")
		(29 "B.CrtYd" user "Package Geometry/Place Bound Bottom")
		(35 "F.Fab" user "Ref Des/Assembly Top")
		(33 "B.Fab" user "Ref Des/Assembly Bottom")
	)
	(footprint ""
		(layer "F.Cu")
		(at 179.939442 -26.240232)
		(property "Reference" "PC2241"
			(at 0 0 0)
			(layer "F.SilkS")
			(hide yes)
			(effects
				(font
					(size 1.27 1.27)
				)
			)
		)
		(property "Value" ""
			(at 0 0 0)
			(layer "F.Fab")
			(effects
				(font
					(size 1.27 1.27)
				)
			)
		)
		(duplicate_pad_numbers_are_jumpers no)
		(fp_line
			(start -0.7874 -0.4064)
			(end 0.7874 -0.4064)
			(stroke
				(width 0.1524)
				(type default)
			)
			(layer "F.SilkS")
		)
		(fp_line
			(start -0.7874 0.4064)
			(end -0.7874 -0.4064)
			(stroke
				(width 0.1524)
				(type default)
			)
			(layer "F.SilkS")
		)
		(fp_line
			(start 0.7874 -0.4064)
			(end 0.7874 0.4064)
			(stroke
				(width 0.1524)
				(type default)
			)
			(layer "F.SilkS")
		)
		(fp_line
			(start 0.7874 0.4064)
			(end -0.7874 0.4064)
			(stroke
				(width 0.1524)
				(type default)
			)
			(layer "F.SilkS")
		)
		(fp_line
			(start -0.67945 -0.305054)
			(end -0.12065 -0.305054)
			(stroke
				(width 0.1)
				(type default)
			)
			(layer "F.Fab")
		)
		(fp_line
			(start -0.67945 0.3048)
			(end -0.67945 -0.305054)
			(stroke
				(width 0.1)
				(type default)
			)
			(layer "F.Fab")
		)
		(fp_line
			(start -0.12065 -0.305054)
			(end -0.12065 -0.2794)
			(stroke
				(width 0.1)
				(type default)
			)
			(layer "F.Fab")
		)
		(fp_line
			(start -0.12065 -0.2794)
			(end 0.12065 -0.2794)
			(stroke
				(width 0.1)
				(type default)
			)
			(layer "F.Fab")
		)
		(fp_line
			(start -0.12065 0.2794)
			(end -0.12065 0.3048)
			(stroke
				(width 0.1)
				(type default)
			)
			(layer "F.Fab")
		)
		(fp_line
			(start -0.12065 0.3048)
			(end -0.67945 0.3048)
			(stroke
				(width 0.1)
				(type default)
			)
			(layer "F.Fab")
		)
		(fp_line
			(start 0.120396 0.2794)
			(end -0.12065 0.2794)
			(stroke
				(width 0.1)
				(type default)
			)
			(layer "F.Fab")
		)
		(fp_line
			(start 0.120396 0.3048)
			(end 0.120396 0.2794)
			(stroke
				(width 0.1)
				(type default)
			)
			(layer "F.Fab")
		)
		(fp_line
			(start 0.12065 -0.3048)
			(end 0.67945 -0.3048)
			(stroke
				(width 0.1)
				(type default)
			)
			(layer "F.Fab")
		)
		(fp_line
			(start 0.12065 -0.2794)
			(end 0.12065 -0.3048)
			(stroke
				(width 0.1)
				(type default)
			)
			(layer "F.Fab")
		)
		(fp_line
			(start 0.67945 -0.3048)
			(end 0.67945 0.3048)
			(stroke
				(width 0.1)
				(type default)
			)
			(layer "F.Fab")
		)
		(fp_line
			(start 0.67945 0.3048)
			(end 0.120396 0.3048)
			(stroke
				(width 0.1)
				(type default)
			)
			(layer "F.Fab")
		)
		(pad "1" smd circle
			(at -0.40005 0)
			(size 0 0)
			(layers "F.Cu" "F.Mask" "F.Paste")
			(net "P12V_SCM_R")
		)
		(pad "2" smd circle
			(at 0.40005 0)
			(size 0 0)
			(layers "F.Cu" "F.Mask" "F.Paste")
			(net "GND")
		)
	)
	(footprint ""
		(layer "F.Cu")
		(at 297.183048 -367.919508)
		(property "Reference" "PR353"
			(at 0 0 0)
			(layer "F.SilkS")
			(hide yes)
			(effects
				(font
					(size 1.27 1.27)
				)
			)
		)
		(property "Value" ""
			(at 0 0 0)
			(layer "F.Fab")
			(effects
				(font
					(size 1.27 1.27)
				)
			)
		)
		(duplicate_pad_numbers_are_jumpers no)
		(fp_line
			(start -0.7874 -0.4064)
			(end 0.7874 -0.4064)
			(stroke
				(width 0.1524)
				(type default)
			)
			(layer "F.SilkS")
		)
		(fp_line
			(start -0.7874 0.4064)
			(end -0.7874 -0.4064)
			(stroke
				(width 0.1524)
				(type default)
			)
			(layer "F.SilkS")
		)
		(fp_line
			(start 0.7874 -0.4064)
			(end 0.7874 0.4064)
			(stroke
				(width 0.1524)
				(type default)
			)
			(layer "F.SilkS")
		)
		(fp_line
			(start 0.7874 0.4064)
			(end -0.7874 0.4064)
			(stroke
				(width 0.1524)
				(type default)
			)
			(layer "F.SilkS")
		)
		(fp_line
			(start -0.67945 -0.305054)
			(end -0.12065 -0.305054)
			(stroke
				(width 0.1)
				(type default)
			)
			(layer "F.Fab")
		)
		(fp_line
			(start -0.67945 0.3048)
			(end -0.67945 -0.305054)
			(stroke
				(width 0.1)
				(type default)
			)
			(layer "F.Fab")
		)
		(fp_line
			(start -0.12065 -0.305054)
			(end -0.12065 -0.2794)
			(stroke
				(width 0.1)
				(type default)
			)
			(layer "F.Fab")
		)
		(fp_line
			(start -0.12065 -0.2794)
			(end 0.12065 -0.2794)
			(stroke
				(width 0.1)
				(type default)
			)
			(layer "F.Fab")
		)
		(fp_line
			(start -0.12065 0.2794)
			(end -0.12065 0.3048)
			(stroke
				(width 0.1)
				(type default)
			)
			(layer "F.Fab")
		)
		(fp_line
			(start -0.12065 0.3048)
			(end -0.67945 0.3048)
			(stroke
				(width 0.1)
				(type default)
			)
			(layer "F.Fab")
		)
		(fp_line
			(start 0.120396 0.2794)
			(end -0.12065 0.2794)
			(stroke
				(width 0.1)
				(type default)
			)
			(layer "F.Fab")
		)
		(fp_line
			(start 0.120396 0.3048)
			(end 0.120396 0.2794)
			(stroke
				(width 0.1)
				(type default)
			)
			(layer "F.Fab")
		)
		(fp_line
			(start 0.12065 -0.3048)
			(end 0.67945 -0.3048)
			(stroke
				(width 0.1)
				(type default)
			)
			(layer "F.Fab")
		)
		(fp_line
			(start 0.12065 -0.2794)
			(end 0.12065 -0.3048)
			(stroke
				(width 0.1)
				(type default)
			)
			(layer "F.Fab")
		)
		(fp_line
			(start 0.67945 -0.3048)
			(end 0.67945 0.3048)
			(stroke
				(width 0.1)
				(type default)
			)
			(layer "F.Fab")
		)
		(fp_line
			(start 0.67945 0.3048)
			(end 0.120396 0.3048)
			(stroke
				(width 0.1)
				(type default)
			)
			(layer "F.Fab")
		)
		(pad "1" smd circle
			(at -0.40005 0)
			(size 0 0)
			(layers "F.Cu" "F.Mask" "F.Paste")
			(net "PVCCFA_EHV_FIVRA_CPU0_LSET2")
		)
		(pad "2" smd circle
			(at 0.40005 0)
			(size 0 0)
			(layers "F.Cu" "F.Mask" "F.Paste")
			(net "GND")
		)
	)
	(footprint ""
		(layer "F.Cu")
		(at 283.32176 -399.04162 90)
		(property "Reference" "U365"
			(at -1.905 -2.25933 90)
			(unlocked yes)
			(layer "F.SilkS")
			(effects
				(font
					(size 0.7874 0.5842)
					(thickness 0.1524)
				)
				(justify left)
			)
		)
		(property "Value" ""
			(at 0 0 90)
			(layer "F.Fab")
			(effects
				(font
					(size 1.27 1.27)
				)
			)
		)
		(duplicate_pad_numbers_are_jumpers no)
		(fp_line
			(start 1.905 -1.651)
			(end 1.905 1.651)
			(stroke
				(width 0.1524)
				(type default)
			)
			(layer "F.SilkS")
		)
		(fp_line
			(start -1.905 -1.651)
			(end 1.905 -1.651)
			(stroke
				(width 0.1524)
				(type default)
			)
			(layer "F.SilkS")
		)
		(fp_line
			(start 1.905 1.651)
			(end -1.905 1.651)
			(stroke
				(width 0.1524)
				(type default)
			)
			(layer "F.SilkS")
		)
		(fp_line
			(start -1.905 1.651)
			(end -1.905 -1.651)
			(stroke
				(width 0.1524)
				(type default)
			)
			(layer "F.SilkS")
		)
		(fp_line
			(start 0.6985 -1.524)
			(end 0.6985 -0.219964)
			(stroke
				(width 0.1)
				(type default)
			)
			(layer "F.Fab")
		)
		(fp_line
			(start -0.649986 -1.524)
			(end 0.6985 -1.524)
			(stroke
				(width 0.1)
				(type default)
			)
			(layer "F.Fab")
		)
		(fp_line
			(start -0.649986 -1.169924)
			(end -0.649986 -1.524)
			(stroke
				(width 0.1)
				(type default)
			)
			(layer "F.Fab")
		)
		(fp_line
			(start -1.249934 -1.169924)
			(end -0.649986 -1.169924)
			(stroke
				(width 0.1)
				(type default)
			)
			(layer "F.Fab")
		)
		(fp_line
			(start -0.6985 -0.729996)
			(end -1.249934 -0.729996)
			(stroke
				(width 0.1)
				(type default)
			)
			(layer "F.Fab")
		)
		(fp_line
			(start -1.249934 -0.729996)
			(end -1.249934 -1.169924)
			(stroke
				(width 0.1)
				(type default)
			)
			(layer "F.Fab")
		)
		(fp_line
			(start 1.249934 -0.219964)
			(end 1.249934 0.219964)
			(stroke
				(width 0.1)
				(type default)
			)
			(layer "F.Fab")
		)
		(fp_line
			(start 0.6985 -0.219964)
			(end 1.249934 -0.219964)
			(stroke
				(width 0.1)
				(type default)
			)
			(layer "F.Fab")
		)
		(fp_line
			(start 1.249934 0.219964)
			(end 0.6985 0.219964)
			(stroke
				(width 0.1)
				(type default)
			)
			(layer "F.Fab")
		)
		(fp_line
			(start 0.6985 0.219964)
			(end 0.6985 1.524)
			(stroke
				(width 0.1)
				(type default)
			)
			(layer "F.Fab")
		)
		(fp_line
			(start -0.6985 0.729996)
			(end -0.6985 -0.729996)
			(stroke
				(width 0.1)
				(type default)
			)
			(layer "F.Fab")
		)
		(fp_line
			(start -1.249934 0.729996)
			(end -0.6985 0.729996)
			(stroke
				(width 0.1)
				(type default)
			)
			(layer "F.Fab")
		)
		(fp_line
			(start -0.649986 1.169924)
			(end -1.249934 1.169924)
			(stroke
				(width 0.1)
				(type default)
			)
			(layer "F.Fab")
		)
		(fp_line
			(start -1.249934 1.169924)
			(end -1.249934 0.729996)
			(stroke
				(width 0.1)
				(type default)
			)
			(layer "F.Fab")
		)
		(fp_line
			(start 0.6985 1.524)
			(end -0.649986 1.524)
			(stroke
				(width 0.1)
				(type default)
			)
			(layer "F.Fab")
		)
		(fp_line
			(start -0.649986 1.524)
			(end -0.649986 1.169924)
			(stroke
				(width 0.1)
				(type default)
			)
			(layer "F.Fab")
		)
		(pad "B" smd rect
			(at -1.1176 -1.016)
			(size 1.016 1.27)
			(layers "F.Cu" "F.Mask" "F.Paste")
			(net "P12V_HSC_TEMP_R")
		)
		(pad "C" smd rect
			(at 1.1176 0)
			(size 1.016 1.27)
			(layers "F.Cu" "F.Mask" "F.Paste")
			(net "P12V_HSC_TEMP_R")
		)
		(pad "E" smd rect
			(at -1.1176 1.016)
			(size 1.016 1.27)
			(layers "F.Cu" "F.Mask" "F.Paste")
			(net "P12V_HSC_TEMP_E")
		)
	)
	(footprint ""
		(layer "F.Cu")
		(at 68.644008 -177.905156 90)
		(property "Reference" "PC2199"
			(at 0 0 90)
			(layer "F.SilkS")
			(hide yes)
			(effects
				(font
					(size 1.27 1.27)
				)
			)
		)
		(property "Value" ""
			(at 0 0 90)
			(layer "F.Fab")
			(effects
				(font
					(size 1.27 1.27)
				)
			)
		)
		(duplicate_pad_numbers_are_jumpers no)
		(fp_line
			(start 2.750058 0.999998)
			(end -2.750058 0.999998)
			(stroke
				(width 0.1524)
				(type default)
			)
			(layer "F.SilkS")
		)
		(fp_circle
			(center 0 0.999998)
			(end 0 3.750056)
			(stroke
				(width 0.1524)
				(type default)
			)
			(fill no)
			(layer "F.SilkS")
		)
		(fp_poly
			(pts
				(arc
					(start 2.750058 0.999998)
					(mid 0 3.750056)
					(end -2.750058 0.999998)
				)
			)
			(stroke
				(width 0)
				(type default)
			)
			(fill yes)
			(layer "F.SilkS")
		)
		(fp_circle
			(center 0 0.999998)
			(end 0 3.750056)
			(stroke
				(width 0.1)
				(type default)
			)
			(fill no)
			(layer "F.Fab")
		)
		(pad "1" thru_hole rect
			(at 0 0 90)
			(size 1.5748 1.5748)
			(drill 1.0668)
			(layers "*.Cu" "*.Mask")
			(remove_unused_layers no)
			(net "PVCCFA_EHV_CPU1")
			(clearance 0)
			(padstack
				(mode front_inner_back)
				(layer "Inner"
					(shape circle)
					(size 1.5748 1.5748)
					(clearance 0)
				)
				(layer "B.Cu"
					(shape rect)
					(size 1.5748 1.5748)
					(clearance 0)
				)
			)
		)
		(pad "2" thru_hole circle
			(at 0 1.999996 90)
			(size 1.5748 1.5748)
			(drill 1.0668)
			(layers "*.Cu" "*.Mask")
			(remove_unused_layers no)
			(net "GND")
			(clearance 0)
		)
	)
	(footprint ""
		(layer "F.Cu")
		(at 63.034164 -160.997392 180)
		(property "Reference" "PR4258"
			(at 0 0 180)
			(layer "F.SilkS")
			(hide yes)
			(effects
				(font
					(size 1.27 1.27)
				)
			)
		)
		(property "Value" ""
			(at 0 0 180)
			(layer "F.Fab")
			(effects
				(font
					(size 1.27 1.27)
				)
			)
		)
		(duplicate_pad_numbers_are_jumpers no)
		(fp_line
			(start 0.7874 0.4064)
			(end -0.7874 0.4064)
			(stroke
				(width 0.1524)
				(type default)
			)
			(layer "F.SilkS")
		)
		(fp_line
			(start 0.7874 -0.4064)
			(end 0.7874 0.4064)
			(stroke
				(width 0.1524)
				(type default)
			)
			(layer "F.SilkS")
		)
		(fp_line
			(start -0.7874 0.4064)
			(end -0.7874 -0.4064)
			(stroke
				(width 0.1524)
				(type default)
			)
			(layer "F.SilkS")
		)
		(fp_line
			(start -0.7874 -0.4064)
			(end 0.7874 -0.4064)
			(stroke
				(width 0.1524)
				(type default)
			)
			(layer "F.SilkS")
		)
		(fp_line
			(start 0.67945 0.3048)
			(end 0.120396 0.3048)
			(stroke
				(width 0.1)
				(type default)
			)
			(layer "F.Fab")
		)
		(fp_line
			(start 0.67945 -0.3048)
			(end 0.67945 0.3048)
			(stroke
				(width 0.1)
				(type default)
			)
			(layer "F.Fab")
		)
		(fp_line
			(start 0.12065 -0.2794)
			(end 0.12065 -0.3048)
			(stroke
				(width 0.1)
				(type default)
			)
			(layer "F.Fab")
		)
		(fp_line
			(start 0.12065 -0.3048)
			(end 0.67945 -0.3048)
			(stroke
				(width 0.1)
				(type default)
			)
			(layer "F.Fab")
		)
		(fp_line
			(start 0.120396 0.3048)
			(end 0.120396 0.2794)
			(stroke
				(width 0.1)
				(type default)
			)
			(layer "F.Fab")
		)
		(fp_line
			(start 0.120396 0.2794)
			(end -0.12065 0.2794)
			(stroke
				(width 0.1)
				(type default)
			)
			(layer "F.Fab")
		)
		(fp_line
			(start -0.12065 0.3048)
			(end -0.67945 0.3048)
			(stroke
				(width 0.1)
				(type default)
			)
			(layer "F.Fab")
		)
		(fp_line
			(start -0.12065 0.2794)
			(end -0.12065 0.3048)
			(stroke
				(width 0.1)
				(type default)
			)
			(layer "F.Fab")
		)
		(fp_line
			(start -0.12065 -0.2794)
			(end 0.12065 -0.2794)
			(stroke
				(width 0.1)
				(type default)
			)
			(layer "F.Fab")
		)
		(fp_line
			(start -0.12065 -0.305054)
			(end -0.12065 -0.2794)
			(stroke
				(width 0.1)
				(type default)
			)
			(layer "F.Fab")
		)
		(fp_line
			(start -0.67945 0.3048)
			(end -0.67945 -0.305054)
			(stroke
				(width 0.1)
				(type default)
			)
			(layer "F.Fab")
		)
		(fp_line
			(start -0.67945 -0.305054)
			(end -0.12065 -0.305054)
			(stroke
				(width 0.1)
				(type default)
			)
			(layer "F.Fab")
		)
		(pad "1" smd circle
			(at -0.40005 0 180)
			(size 0 0)
			(layers "F.Cu" "F.Mask" "F.Paste")
			(net "PVCCD_HV_CPU1")
		)
		(pad "2" smd circle
			(at 0.40005 0 180)
			(size 0 0)
			(layers "F.Cu" "F.Mask" "F.Paste")
			(net "GND")
		)
	)
	(footprint ""
		(layer "F.Cu")
		(at 106.7181 -411.582108 180)
		(property "Reference" "R4479"
			(at 0 0 180)
			(layer "F.SilkS")
			(hide yes)
			(effects
				(font
					(size 1.27 1.27)
				)
			)
		)
		(property "Value" ""
			(at 0 0 180)
			(layer "F.Fab")
			(effects
				(font
					(size 1.27 1.27)
				)
			)
		)
		(duplicate_pad_numbers_are_jumpers no)
		(fp_line
			(start 0.7874 0.4064)
			(end -0.7874 0.4064)
			(stroke
				(width 0.1524)
				(type default)
			)
			(layer "F.SilkS")
		)
		(fp_line
			(start 0.7874 -0.4064)
			(end 0.7874 0.4064)
			(stroke
				(width 0.1524)
				(type default)
			)
			(layer "F.SilkS")
		)
		(fp_line
			(start -0.7874 0.4064)
			(end -0.7874 -0.4064)
			(stroke
				(width 0.1524)
				(type default)
			)
			(layer "F.SilkS")
		)
		(fp_line
			(start -0.7874 -0.4064)
			(end 0.7874 -0.4064)
			(stroke
				(width 0.1524)
				(type default)
			)
			(layer "F.SilkS")
		)
		(fp_line
			(start 0.67945 0.3048)
			(end 0.120396 0.3048)
			(stroke
				(width 0.1)
				(type default)
			)
			(layer "F.Fab")
		)
		(fp_line
			(start 0.67945 -0.3048)
			(end 0.67945 0.3048)
			(stroke
				(width 0.1)
				(type default)
			)
			(layer "F.Fab")
		)
		(fp_line
			(start 0.12065 -0.2794)
			(end 0.12065 -0.3048)
			(stroke
				(width 0.1)
				(type default)
			)
			(layer "F.Fab")
		)
		(fp_line
			(start 0.12065 -0.3048)
			(end 0.67945 -0.3048)
			(stroke
				(width 0.1)
				(type default)
			)
			(layer "F.Fab")
		)
		(fp_line
			(start 0.120396 0.3048)
			(end 0.120396 0.2794)
			(stroke
				(width 0.1)
				(type default)
			)
			(layer "F.Fab")
		)
		(fp_line
			(start 0.120396 0.2794)
			(end -0.12065 0.2794)
			(stroke
				(width 0.1)
				(type default)
			)
			(layer "F.Fab")
		)
		(fp_line
			(start -0.12065 0.3048)
			(end -0.67945 0.3048)
			(stroke
				(width 0.1)
				(type default)
			)
			(layer "F.Fab")
		)
		(fp_line
			(start -0.12065 0.2794)
			(end -0.12065 0.3048)
			(stroke
				(width 0.1)
				(type default)
			)
			(layer "F.Fab")
		)
		(fp_line
			(start -0.12065 -0.2794)
			(end 0.12065 -0.2794)
			(stroke
				(width 0.1)
				(type default)
			)
			(layer "F.Fab")
		)
		(fp_line
			(start -0.12065 -0.305054)
			(end -0.12065 -0.2794)
			(stroke
				(width 0.1)
				(type default)
			)
			(layer "F.Fab")
		)
		(fp_line
			(start -0.67945 0.3048)
			(end -0.67945 -0.305054)
			(stroke
				(width 0.1)
				(type default)
			)
			(layer "F.Fab")
		)
		(fp_line
			(start -0.67945 -0.305054)
			(end -0.12065 -0.305054)
			(stroke
				(width 0.1)
				(type default)
			)
			(layer "F.Fab")
		)
		(pad "1" smd circle
			(at -0.40005 0 180)
			(size 0 0)
			(layers "F.Cu" "F.Mask" "F.Paste")
			(net "FM_9ZXL045_2_OE_N")
		)
		(pad "2" smd circle
			(at 0.40005 0 180)
			(size 0 0)
			(layers "F.Cu" "F.Mask" "F.Paste")
			(net "CLK_GPU_2_OE_N")
		)
	)
)
